(kicad_pcb
	(version 20260206)
	(generator "pcbnew")
	(generator_version "10.0")
	(general
		(thickness 1.6)
		(legacy_teardrops no)
	)
	(paper "A4")
	(title_block
		(title "01162023_DA0F0TEBIF0_F0T_Expander_BD_F_brd_V02_OCP.brd")
		(comment 1 "Grand Teton / footprints 150-156 of 9728")
	)
	(layers
		(0 "F.Cu" signal "TOP")
		(4 "In1.Cu" signal "GND")
		(6 "In2.Cu" signal "VCC")
		(8 "In3.Cu" signal "VCC1")
		(10 "In4.Cu" signal "GND1")
		(12 "In5.Cu" signal "IN1")
		(14 "In6.Cu" signal "GND2")
		(16 "In7.Cu" signal "IN2")
		(18 "In8.Cu" signal "GND3")
		(20 "In9.Cu" signal "IN3")
		(22 "In10.Cu" signal "GND4")
		(24 "In11.Cu" signal "IN4")
		(26 "In12.Cu" signal "GND5")
		(28 "In13.Cu" signal "IN5")
		(30 "In14.Cu" signal "GND6")
		(32 "In15.Cu" signal "IN6")
		(34 "In16.Cu" signal "GND7")
		(2 "B.Cu" signal "BOTTOM")
		(9 "F.Adhes" user "F.Adhesive")
		(11 "B.Adhes" user "B.Adhesive")
		(13 "F.Paste" user "Package Geometry/Pastemask Top")
		(15 "B.Paste" user "Package Geometry/Pastemask Bottom")
		(5 "F.SilkS" user "Ref Des/Silkscreen Top")
		(7 "B.SilkS" user "Ref Des/Silkscreen Bottom")
		(1 "F.Mask" user "Board Geometry/Soldermask Top")
		(3 "B.Mask" user "Board Geometry/Soldermask Bottom")
		(17 "Dwgs.User" user "User.Drawings")
		(19 "Cmts.User" user "User.Comments")
		(21 "Eco1.User" user "User.Eco1")
		(23 "Eco2.User" user "User.Eco2")
		(25 "Edge.Cuts" user "Board Geometry/Outline")
		(27 "Margin" user)
		(31 "F.CrtYd" user "Package Geometry/Place Bound Top")
		(29 "B.CrtYd" user "Package Geometry/Place Bound Bottom")
		(35 "F.Fab" user "Ref Des/Assembly Top")
		(33 "B.Fab" user "Ref Des/Assembly Bottom")
	)
	(footprint ""
		(layer "F.Cu")
		(at 226.33686 -275.602192 135)
		(property "Reference" "C630"
			(at 0 0 135)
			(layer "F.SilkS")
			(hide yes)
			(effects
				(font
					(size 1.27 1.27)
				)
			)
		)
		(property "Value" ""
			(at 0 0 135)
			(layer "F.Fab")
			(effects
				(font
					(size 1.27 1.27)
				)
			)
		)
		(duplicate_pad_numbers_are_jumpers no)
		(fp_line
			(start 0.787389 -0.406267)
			(end 0.787389 0.406267)
			(stroke
				(width 0.1524)
				(type default)
			)
			(layer "F.SilkS")
		)
		(fp_line
			(start 0.787389 0.406267)
			(end -0.787389 0.406267)
			(stroke
				(width 0.1524)
				(type default)
			)
			(layer "F.SilkS")
		)
		(fp_line
			(start -0.787389 -0.406267)
			(end 0.787389 -0.406267)
			(stroke
				(width 0.1524)
				(type default)
			)
			(layer "F.SilkS")
		)
		(fp_line
			(start -0.787389 0.406267)
			(end -0.787389 -0.406267)
			(stroke
				(width 0.1524)
				(type default)
			)
			(layer "F.SilkS")
		)
		(fp_line
			(start 0.679446 -0.30479)
			(end 0.679446 0.30479)
			(stroke
				(width 0.1)
				(type default)
			)
			(layer "F.Fab")
		)
		(fp_line
			(start 0.120515 -0.30479)
			(end 0.679446 -0.30479)
			(stroke
				(width 0.1)
				(type default)
			)
			(layer "F.Fab")
		)
		(fp_line
			(start 0.120695 -0.279466)
			(end 0.120515 -0.30479)
			(stroke
				(width 0.1)
				(type default)
			)
			(layer "F.Fab")
		)
		(fp_line
			(start 0.679446 0.30479)
			(end 0.120515 0.30479)
			(stroke
				(width 0.1)
				(type default)
			)
			(layer "F.Fab")
		)
		(fp_line
			(start -0.120695 -0.304969)
			(end -0.120695 -0.279466)
			(stroke
				(width 0.1)
				(type default)
			)
			(layer "F.Fab")
		)
		(fp_line
			(start -0.120695 -0.279466)
			(end 0.120695 -0.279466)
			(stroke
				(width 0.1)
				(type default)
			)
			(layer "F.Fab")
		)
		(fp_line
			(start 0.120335 0.279466)
			(end -0.120695 0.279466)
			(stroke
				(width 0.1)
				(type default)
			)
			(layer "F.Fab")
		)
		(fp_line
			(start 0.120515 0.30479)
			(end 0.120335 0.279466)
			(stroke
				(width 0.1)
				(type default)
			)
			(layer "F.Fab")
		)
		(fp_line
			(start -0.679446 -0.305149)
			(end -0.120695 -0.304969)
			(stroke
				(width 0.1)
				(type default)
			)
			(layer "F.Fab")
		)
		(fp_line
			(start -0.120695 0.279466)
			(end -0.120515 0.30479)
			(stroke
				(width 0.1)
				(type default)
			)
			(layer "F.Fab")
		)
		(fp_line
			(start -0.120515 0.30479)
			(end -0.679446 0.30479)
			(stroke
				(width 0.1)
				(type default)
			)
			(layer "F.Fab")
		)
		(fp_line
			(start -0.679446 0.30479)
			(end -0.679446 -0.305149)
			(stroke
				(width 0.1)
				(type default)
			)
			(layer "F.Fab")
		)
		(pad "1" smd circle
			(at -0.40005 0 135)
			(size 0 0)
			(layers "F.Cu" "F.Mask" "F.Paste")
			(net "P12V_PEX1_P1V25_VIN_P")
		)
		(pad "2" smd circle
			(at 0.40005 0 135)
			(size 0 0)
			(layers "F.Cu" "F.Mask" "F.Paste")
			(net "P12V_PEX1_P1V25_VIN_N")
		)
	)
	(footprint ""
		(layer "F.Cu")
		(at 201.06894 -405.895302 -90)
		(property "Reference" "C4006"
			(at 0 0 270)
			(layer "F.SilkS")
			(hide yes)
			(effects
				(font
					(size 1.27 1.27)
				)
			)
		)
		(property "Value" ""
			(at 0 0 270)
			(layer "F.Fab")
			(effects
				(font
					(size 1.27 1.27)
				)
			)
		)
		(duplicate_pad_numbers_are_jumpers no)
		(fp_line
			(start -0.7874 0.4064)
			(end -0.7874 -0.4064)
			(stroke
				(width 0.1524)
				(type default)
			)
			(layer "F.SilkS")
		)
		(fp_line
			(start 0.7874 0.4064)
			(end -0.7874 0.4064)
			(stroke
				(width 0.1524)
				(type default)
			)
			(layer "F.SilkS")
		)
		(fp_line
			(start -0.7874 -0.4064)
			(end 0.7874 -0.4064)
			(stroke
				(width 0.1524)
				(type default)
			)
			(layer "F.SilkS")
		)
		(fp_line
			(start 0.7874 -0.4064)
			(end 0.7874 0.4064)
			(stroke
				(width 0.1524)
				(type default)
			)
			(layer "F.SilkS")
		)
		(fp_line
			(start -0.67945 0.3048)
			(end -0.67945 -0.305054)
			(stroke
				(width 0.1)
				(type default)
			)
			(layer "F.Fab")
		)
		(fp_line
			(start -0.12065 0.3048)
			(end -0.67945 0.3048)
			(stroke
				(width 0.1)
				(type default)
			)
			(layer "F.Fab")
		)
		(fp_line
			(start 0.120396 0.3048)
			(end 0.120396 0.2794)
			(stroke
				(width 0.1)
				(type default)
			)
			(layer "F.Fab")
		)
		(fp_line
			(start 0.67945 0.3048)
			(end 0.120396 0.3048)
			(stroke
				(width 0.1)
				(type default)
			)
			(layer "F.Fab")
		)
		(fp_line
			(start -0.12065 0.2794)
			(end -0.12065 0.3048)
			(stroke
				(width 0.1)
				(type default)
			)
			(layer "F.Fab")
		)
		(fp_line
			(start 0.120396 0.2794)
			(end -0.12065 0.2794)
			(stroke
				(width 0.1)
				(type default)
			)
			(layer "F.Fab")
		)
		(fp_line
			(start -0.12065 -0.2794)
			(end 0.12065 -0.2794)
			(stroke
				(width 0.1)
				(type default)
			)
			(layer "F.Fab")
		)
		(fp_line
			(start 0.12065 -0.2794)
			(end 0.12065 -0.3048)
			(stroke
				(width 0.1)
				(type default)
			)
			(layer "F.Fab")
		)
		(fp_line
			(start 0.12065 -0.3048)
			(end 0.67945 -0.3048)
			(stroke
				(width 0.1)
				(type default)
			)
			(layer "F.Fab")
		)
		(fp_line
			(start 0.67945 -0.3048)
			(end 0.67945 0.3048)
			(stroke
				(width 0.1)
				(type default)
			)
			(layer "F.Fab")
		)
		(fp_line
			(start -0.67945 -0.305054)
			(end -0.12065 -0.305054)
			(stroke
				(width 0.1)
				(type default)
			)
			(layer "F.Fab")
		)
		(fp_line
			(start -0.12065 -0.305054)
			(end -0.12065 -0.2794)
			(stroke
				(width 0.1)
				(type default)
			)
			(layer "F.Fab")
		)
		(pad "1" smd circle
			(at -0.40005 0 270)
			(size 0 0)
			(layers "F.Cu" "F.Mask" "F.Paste")
			(net "MB_HSC_EN")
		)
		(pad "2" smd circle
			(at 0.40005 0 270)
			(size 0 0)
			(layers "F.Cu" "F.Mask" "F.Paste")
			(net "GND")
		)
	)
	(footprint ""
		(layer "F.Cu")
		(at 355.854 -166.624)
		(property "Reference" "R4744"
			(at 0 0 0)
			(layer "F.SilkS")
			(hide yes)
			(effects
				(font
					(size 1.27 1.27)
				)
			)
		)
		(property "Value" ""
			(at 0 0 0)
			(layer "F.Fab")
			(effects
				(font
					(size 1.27 1.27)
				)
			)
		)
		(duplicate_pad_numbers_are_jumpers no)
		(fp_line
			(start -0.7874 -0.4064)
			(end 0.7874 -0.4064)
			(stroke
				(width 0.1524)
				(type default)
			)
			(layer "F.SilkS")
		)
		(fp_line
			(start -0.7874 0.4064)
			(end -0.7874 -0.4064)
			(stroke
				(width 0.1524)
				(type default)
			)
			(layer "F.SilkS")
		)
		(fp_line
			(start 0.7874 -0.4064)
			(end 0.7874 0.4064)
			(stroke
				(width 0.1524)
				(type default)
			)
			(layer "F.SilkS")
		)
		(fp_line
			(start 0.7874 0.4064)
			(end -0.7874 0.4064)
			(stroke
				(width 0.1524)
				(type default)
			)
			(layer "F.SilkS")
		)
		(fp_line
			(start -0.67945 -0.305054)
			(end -0.12065 -0.305054)
			(stroke
				(width 0.1)
				(type default)
			)
			(layer "F.Fab")
		)
		(fp_line
			(start -0.67945 0.3048)
			(end -0.67945 -0.305054)
			(stroke
				(width 0.1)
				(type default)
			)
			(layer "F.Fab")
		)
		(fp_line
			(start -0.12065 -0.305054)
			(end -0.12065 -0.2794)
			(stroke
				(width 0.1)
				(type default)
			)
			(layer "F.Fab")
		)
		(fp_line
			(start -0.12065 -0.2794)
			(end 0.12065 -0.2794)
			(stroke
				(width 0.1)
				(type default)
			)
			(layer "F.Fab")
		)
		(fp_line
			(start -0.12065 0.2794)
			(end -0.12065 0.3048)
			(stroke
				(width 0.1)
				(type default)
			)
			(layer "F.Fab")
		)
		(fp_line
			(start -0.12065 0.3048)
			(end -0.67945 0.3048)
			(stroke
				(width 0.1)
				(type default)
			)
			(layer "F.Fab")
		)
		(fp_line
			(start 0.120396 0.2794)
			(end -0.12065 0.2794)
			(stroke
				(width 0.1)
				(type default)
			)
			(layer "F.Fab")
		)
		(fp_line
			(start 0.120396 0.3048)
			(end 0.120396 0.2794)
			(stroke
				(width 0.1)
				(type default)
			)
			(layer "F.Fab")
		)
		(fp_line
			(start 0.12065 -0.3048)
			(end 0.67945 -0.3048)
			(stroke
				(width 0.1)
				(type default)
			)
			(layer "F.Fab")
		)
		(fp_line
			(start 0.12065 -0.2794)
			(end 0.12065 -0.3048)
			(stroke
				(width 0.1)
				(type default)
			)
			(layer "F.Fab")
		)
		(fp_line
			(start 0.67945 -0.3048)
			(end 0.67945 0.3048)
			(stroke
				(width 0.1)
				(type default)
			)
			(layer "F.Fab")
		)
		(fp_line
			(start 0.67945 0.3048)
			(end 0.120396 0.3048)
			(stroke
				(width 0.1)
				(type default)
			)
			(layer "F.Fab")
		)
		(pad "1" smd circle
			(at -0.40005 0)
			(size 0 0)
			(layers "F.Cu" "F.Mask" "F.Paste")
			(net "NIC5_PEX_PWR_EN_R")
		)
		(pad "2" smd circle
			(at 0.40005 0)
			(size 0 0)
			(layers "F.Cu" "F.Mask" "F.Paste")
			(net "GND")
		)
	)
	(footprint ""
		(layer "F.Cu")
		(at 342.624918 -201.168 90)
		(property "Reference" "R6416"
			(at 0 0 90)
			(layer "F.SilkS")
			(hide yes)
			(effects
				(font
					(size 1.27 1.27)
				)
			)
		)
		(property "Value" ""
			(at 0 0 90)
			(layer "F.Fab")
			(effects
				(font
					(size 1.27 1.27)
				)
			)
		)
		(duplicate_pad_numbers_are_jumpers no)
		(fp_line
			(start 0.7874 -0.4064)
			(end 0.7874 0.4064)
			(stroke
				(width 0.1524)
				(type default)
			)
			(layer "F.SilkS")
		)
		(fp_line
			(start -0.7874 -0.4064)
			(end 0.7874 -0.4064)
			(stroke
				(width 0.1524)
				(type default)
			)
			(layer "F.SilkS")
		)
		(fp_line
			(start 0.7874 0.4064)
			(end -0.7874 0.4064)
			(stroke
				(width 0.1524)
				(type default)
			)
			(layer "F.SilkS")
		)
		(fp_line
			(start -0.7874 0.4064)
			(end -0.7874 -0.4064)
			(stroke
				(width 0.1524)
				(type default)
			)
			(layer "F.SilkS")
		)
		(fp_line
			(start -0.12065 -0.305054)
			(end -0.12065 -0.2794)
			(stroke
				(width 0.1)
				(type default)
			)
			(layer "F.Fab")
		)
		(fp_line
			(start -0.67945 -0.305054)
			(end -0.12065 -0.305054)
			(stroke
				(width 0.1)
				(type default)
			)
			(layer "F.Fab")
		)
		(fp_line
			(start 0.67945 -0.3048)
			(end 0.67945 0.3048)
			(stroke
				(width 0.1)
				(type default)
			)
			(layer "F.Fab")
		)
		(fp_line
			(start 0.12065 -0.3048)
			(end 0.67945 -0.3048)
			(stroke
				(width 0.1)
				(type default)
			)
			(layer "F.Fab")
		)
		(fp_line
			(start 0.12065 -0.2794)
			(end 0.12065 -0.3048)
			(stroke
				(width 0.1)
				(type default)
			)
			(layer "F.Fab")
		)
		(fp_line
			(start -0.12065 -0.2794)
			(end 0.12065 -0.2794)
			(stroke
				(width 0.1)
				(type default)
			)
			(layer "F.Fab")
		)
		(fp_line
			(start 0.120396 0.2794)
			(end -0.12065 0.2794)
			(stroke
				(width 0.1)
				(type default)
			)
			(layer "F.Fab")
		)
		(fp_line
			(start -0.12065 0.2794)
			(end -0.12065 0.3048)
			(stroke
				(width 0.1)
				(type default)
			)
			(layer "F.Fab")
		)
		(fp_line
			(start 0.67945 0.3048)
			(end 0.120396 0.3048)
			(stroke
				(width 0.1)
				(type default)
			)
			(layer "F.Fab")
		)
		(fp_line
			(start 0.120396 0.3048)
			(end 0.120396 0.2794)
			(stroke
				(width 0.1)
				(type default)
			)
			(layer "F.Fab")
		)
		(fp_line
			(start -0.12065 0.3048)
			(end -0.67945 0.3048)
			(stroke
				(width 0.1)
				(type default)
			)
			(layer "F.Fab")
		)
		(fp_line
			(start -0.67945 0.3048)
			(end -0.67945 -0.305054)
			(stroke
				(width 0.1)
				(type default)
			)
			(layer "F.Fab")
		)
		(pad "1" smd circle
			(at -0.40005 0 90)
			(size 0 0)
			(layers "F.Cu" "F.Mask" "F.Paste")
			(net "FPGA_PEX0_MODE_SEL2_R")
		)
		(pad "2" smd circle
			(at 0.40005 0 90)
			(size 0 0)
			(layers "F.Cu" "F.Mask" "F.Paste")
			(net "FPGA_PEX0_MODE_SEL2")
		)
	)
	(footprint ""
		(layer "F.Cu")
		(at 260.606286 -250.070874 -90)
		(property "Reference" "R1334"
			(at 0 0 270)
			(layer "F.SilkS")
			(hide yes)
			(effects
				(font
					(size 1.27 1.27)
				)
			)
		)
		(property "Value" ""
			(at 0 0 270)
			(layer "F.Fab")
			(effects
				(font
					(size 1.27 1.27)
				)
			)
		)
		(duplicate_pad_numbers_are_jumpers no)
		(fp_line
			(start -0.7874 0.4064)
			(end -0.7874 -0.4064)
			(stroke
				(width 0.1524)
				(type default)
			)
			(layer "F.SilkS")
		)
		(fp_line
			(start 0.7874 0.4064)
			(end -0.7874 0.4064)
			(stroke
				(width 0.1524)
				(type default)
			)
			(layer "F.SilkS")
		)
		(fp_line
			(start -0.7874 -0.4064)
			(end 0.7874 -0.4064)
			(stroke
				(width 0.1524)
				(type default)
			)
			(layer "F.SilkS")
		)
		(fp_line
			(start 0.7874 -0.4064)
			(end 0.7874 0.4064)
			(stroke
				(width 0.1524)
				(type default)
			)
			(layer "F.SilkS")
		)
		(fp_line
			(start -0.67945 0.3048)
			(end -0.67945 -0.305054)
			(stroke
				(width 0.1)
				(type default)
			)
			(layer "F.Fab")
		)
		(fp_line
			(start -0.12065 0.3048)
			(end -0.67945 0.3048)
			(stroke
				(width 0.1)
				(type default)
			)
			(layer "F.Fab")
		)
		(fp_line
			(start 0.120396 0.3048)
			(end 0.120396 0.2794)
			(stroke
				(width 0.1)
				(type default)
			)
			(layer "F.Fab")
		)
		(fp_line
			(start 0.67945 0.3048)
			(end 0.120396 0.3048)
			(stroke
				(width 0.1)
				(type default)
			)
			(layer "F.Fab")
		)
		(fp_line
			(start -0.12065 0.2794)
			(end -0.12065 0.3048)
			(stroke
				(width 0.1)
				(type default)
			)
			(layer "F.Fab")
		)
		(fp_line
			(start 0.120396 0.2794)
			(end -0.12065 0.2794)
			(stroke
				(width 0.1)
				(type default)
			)
			(layer "F.Fab")
		)
		(fp_line
			(start -0.12065 -0.2794)
			(end 0.12065 -0.2794)
			(stroke
				(width 0.1)
				(type default)
			)
			(layer "F.Fab")
		)
		(fp_line
			(start 0.12065 -0.2794)
			(end 0.12065 -0.3048)
			(stroke
				(width 0.1)
				(type default)
			)
			(layer "F.Fab")
		)
		(fp_line
			(start 0.12065 -0.3048)
			(end 0.67945 -0.3048)
			(stroke
				(width 0.1)
				(type default)
			)
			(layer "F.Fab")
		)
		(fp_line
			(start 0.67945 -0.3048)
			(end 0.67945 0.3048)
			(stroke
				(width 0.1)
				(type default)
			)
			(layer "F.Fab")
		)
		(fp_line
			(start -0.67945 -0.305054)
			(end -0.12065 -0.305054)
			(stroke
				(width 0.1)
				(type default)
			)
			(layer "F.Fab")
		)
		(fp_line
			(start -0.12065 -0.305054)
			(end -0.12065 -0.2794)
			(stroke
				(width 0.1)
				(type default)
			)
			(layer "F.Fab")
		)
		(pad "1" smd circle
			(at -0.40005 0 270)
			(size 0 0)
			(layers "F.Cu" "F.Mask" "F.Paste")
			(net "PEX2_DBG_MODE3")
		)
		(pad "2" smd circle
			(at 0.40005 0 270)
			(size 0 0)
			(layers "F.Cu" "F.Mask" "F.Paste")
			(net "P1V8_PEX")
		)
	)
	(footprint ""
		(layer "F.Cu")
		(at 353.822 -166.624)
		(property "Reference" "R4777"
			(at 0 0 0)
			(layer "F.SilkS")
			(hide yes)
			(effects
				(font
					(size 1.27 1.27)
				)
			)
		)
		(property "Value" ""
			(at 0 0 0)
			(layer "F.Fab")
			(effects
				(font
					(size 1.27 1.27)
				)
			)
		)
		(duplicate_pad_numbers_are_jumpers no)
		(fp_line
			(start -0.7874 -0.4064)
			(end 0.7874 -0.4064)
			(stroke
				(width 0.1524)
				(type default)
			)
			(layer "F.SilkS")
		)
		(fp_line
			(start -0.7874 0.4064)
			(end -0.7874 -0.4064)
			(stroke
				(width 0.1524)
				(type default)
			)
			(layer "F.SilkS")
		)
		(fp_line
			(start 0.7874 -0.4064)
			(end 0.7874 0.4064)
			(stroke
				(width 0.1524)
				(type default)
			)
			(layer "F.SilkS")
		)
		(fp_line
			(start 0.7874 0.4064)
			(end -0.7874 0.4064)
			(stroke
				(width 0.1524)
				(type default)
			)
			(layer "F.SilkS")
		)
		(fp_line
			(start -0.67945 -0.305054)
			(end -0.12065 -0.305054)
			(stroke
				(width 0.1)
				(type default)
			)
			(layer "F.Fab")
		)
		(fp_line
			(start -0.67945 0.3048)
			(end -0.67945 -0.305054)
			(stroke
				(width 0.1)
				(type default)
			)
			(layer "F.Fab")
		)
		(fp_line
			(start -0.12065 -0.305054)
			(end -0.12065 -0.2794)
			(stroke
				(width 0.1)
				(type default)
			)
			(layer "F.Fab")
		)
		(fp_line
			(start -0.12065 -0.2794)
			(end 0.12065 -0.2794)
			(stroke
				(width 0.1)
				(type default)
			)
			(layer "F.Fab")
		)
		(fp_line
			(start -0.12065 0.2794)
			(end -0.12065 0.3048)
			(stroke
				(width 0.1)
				(type default)
			)
			(layer "F.Fab")
		)
		(fp_line
			(start -0.12065 0.3048)
			(end -0.67945 0.3048)
			(stroke
				(width 0.1)
				(type default)
			)
			(layer "F.Fab")
		)
		(fp_line
			(start 0.120396 0.2794)
			(end -0.12065 0.2794)
			(stroke
				(width 0.1)
				(type default)
			)
			(layer "F.Fab")
		)
		(fp_line
			(start 0.120396 0.3048)
			(end 0.120396 0.2794)
			(stroke
				(width 0.1)
				(type default)
			)
			(layer "F.Fab")
		)
		(fp_line
			(start 0.12065 -0.3048)
			(end 0.67945 -0.3048)
			(stroke
				(width 0.1)
				(type default)
			)
			(layer "F.Fab")
		)
		(fp_line
			(start 0.12065 -0.2794)
			(end 0.12065 -0.3048)
			(stroke
				(width 0.1)
				(type default)
			)
			(layer "F.Fab")
		)
		(fp_line
			(start 0.67945 -0.3048)
			(end 0.67945 0.3048)
			(stroke
				(width 0.1)
				(type default)
			)
			(layer "F.Fab")
		)
		(fp_line
			(start 0.67945 0.3048)
			(end 0.120396 0.3048)
			(stroke
				(width 0.1)
				(type default)
			)
			(layer "F.Fab")
		)
		(pad "1" smd circle
			(at -0.40005 0)
			(size 0 0)
			(layers "F.Cu" "F.Mask" "F.Paste")
			(net "NIC5_PEX_PWR_EN")
		)
		(pad "2" smd circle
			(at 0.40005 0)
			(size 0 0)
			(layers "F.Cu" "F.Mask" "F.Paste")
			(net "NIC5_PEX_PWR_EN_R")
		)
	)
	(footprint ""
		(layer "F.Cu")
		(at 231.874314 -261.137654 180)
		(property "Reference" "C4336"
			(at 0 0 180)
			(layer "F.SilkS")
			(hide yes)
			(effects
				(font
					(size 1.27 1.27)
				)
			)
		)
		(property "Value" ""
			(at 0 0 180)
			(layer "F.Fab")
			(effects
				(font
					(size 1.27 1.27)
				)
			)
		)
		(duplicate_pad_numbers_are_jumpers no)
		(fp_line
			(start 0.299974 0.150114)
			(end -0.299974 0.150114)
			(stroke
				(width 0.1)
				(type default)
			)
			(layer "F.Fab")
		)
		(fp_line
			(start 0.299974 -0.150114)
			(end 0.299974 0.150114)
			(stroke
				(width 0.1)
				(type default)
			)
			(layer "F.Fab")
		)
		(fp_line
			(start -0.299974 0.150114)
			(end -0.299974 -0.150114)
			(stroke
				(width 0.1)
				(type default)
			)
			(layer "F.Fab")
		)
		(fp_line
			(start -0.299974 -0.150114)
			(end 0.299974 -0.150114)
			(stroke
				(width 0.1)
				(type default)
			)
			(layer "F.Fab")
		)
		(pad "1" smd rect
			(at -0.2667 0 180)
			(size 0.3048 0.381)
			(layers "F.Cu" "F.Mask" "F.Paste")
			(net "P1V25_SERDES_VDDPLL_PEX2")
		)
		(pad "2" smd rect
			(at 0.2667 0 180)
			(size 0.3048 0.381)
			(layers "F.Cu" "F.Mask" "F.Paste")
			(net "GND")
		)
	)
)
